# SCM (Grand Teton) — schematic netlist excerpt (pin names and nets, part order shuffled) for the footprints in the layout excerpt that follows; sources: Cadence DE-HDL packaged netlist, KiCad conversion of 12092022_DA0F0TMDCD0_F0T_Management_Board_D_brd_V3_OCP.brd

R232  Q_RES  0 5% EMPTY  pkg 0402LF  page 17 : A = P1V8_AUX ; B = P3V3_P1V8_I2C_I3C
R19  Q_RES  0 5% CHIP  pkg 0402LF  page 15 : A = V_VGAHS_R ; B = V_VGAHS

(kicad_pcb
	(version 20260206)
	(generator "pcbnew")
	(generator_version "10.0")
	(general
		(thickness 1.6)
		(legacy_teardrops no)
	)
	(paper "A4")
	(title_block
		(title "12092022_DA0F0TMDCD0_F0T_Management_Board_D_brd_V3_OCP.brd")
		(comment 1 "Grand Teton / footprints 686-687 of 1440")
	)
	(layers
		(0 "F.Cu" signal "TOP")
		(4 "In1.Cu" signal "GND")
		(6 "In2.Cu" signal "IN1")
		(8 "In3.Cu" signal "GND1")
		(10 "In4.Cu" signal "IN2")
		(12 "In5.Cu" signal "VCC")
		(14 "In6.Cu" signal "VCC1")
		(16 "In7.Cu" signal "IN3")
		(18 "In8.Cu" signal "GND2")
		(20 "In9.Cu" signal "IN4")
		(22 "In10.Cu" signal "GND3")
		(2 "B.Cu" signal "BOTTOM")
		(9 "F.Adhes" user "F.Adhesive")
		(11 "B.Adhes" user "B.Adhesive")
		(13 "F.Paste" user "Package Geometry/Pastemask Top")
		(15 "B.Paste" user "Package Geometry/Pastemask Bottom")
		(5 "F.SilkS" user "Ref Des/Silkscreen Top")
		(7 "B.SilkS" user "Ref Des/Silkscreen Bottom")
		(1 "F.Mask" user "Board Geometry/Soldermask Top")
		(3 "B.Mask" user "Board Geometry/Soldermask Bottom")
		(17 "Dwgs.User" user "User.Drawings")
		(19 "Cmts.User" user "User.Comments")
		(21 "Eco1.User" user "User.Eco1")
		(23 "Eco2.User" user "User.Eco2")
		(25 "Edge.Cuts" user "Board Geometry/Outline")
		(27 "Margin" user)
		(31 "F.CrtYd" user "Package Geometry/Place Bound Top")
		(29 "B.CrtYd" user "Package Geometry/Place Bound Bottom")
		(35 "F.Fab" user "Ref Des/Assembly Top")
		(33 "B.Fab" user "Ref Des/Assembly Bottom")
	)
	(footprint ""
		(layer "F.Cu")
		(at 38.354 -36.068 180)
		(property "Reference" "R232"
			(at 0 0 180)
			(layer "F.SilkS")
			(hide yes)
			(effects
				(font
					(size 1.27 1.27)
				)
			)
		)
		(property "Value" ""
			(at 0 0 180)
			(layer "F.Fab")
			(effects
				(font
					(size 1.27 1.27)
				)
			)
		)
		(duplicate_pad_numbers_are_jumpers no)
		(fp_line
			(start 0.7874 0.4064)
			(end -0.7874 0.4064)
			(stroke
				(width 0.1524)
				(type default)
			)
			(layer "F.SilkS")
		)
		(fp_line
			(start 0.7874 -0.4064)
			(end 0.7874 0.4064)
			(stroke
				(width 0.1524)
				(type default)
			)
			(layer "F.SilkS")
		)
		(fp_line
			(start -0.7874 0.4064)
			(end -0.7874 -0.4064)
			(stroke
				(width 0.1524)
				(type default)
			)
			(layer "F.SilkS")
		)
		(fp_line
			(start -0.7874 -0.4064)
			(end 0.7874 -0.4064)
			(stroke
				(width 0.1524)
				(type default)
			)
			(layer "F.SilkS")
		)
		(fp_line
			(start 0.67945 0.3048)
			(end 0.120396 0.3048)
			(stroke
				(width 0.1)
				(type default)
			)
			(layer "F.Fab")
		)
		(fp_line
			(start 0.67945 -0.3048)
			(end 0.67945 0.3048)
			(stroke
				(width 0.1)
				(type default)
			)
			(layer "F.Fab")
		)
		(fp_line
			(start 0.12065 -0.2794)
			(end 0.12065 -0.3048)
			(stroke
				(width 0.1)
				(type default)
			)
			(layer "F.Fab")
		)
		(fp_line
			(start 0.12065 -0.3048)
			(end 0.67945 -0.3048)
			(stroke
				(width 0.1)
				(type default)
			)
			(layer "F.Fab")
		)
		(fp_line
			(start 0.120396 0.3048)
			(end 0.120396 0.2794)
			(stroke
				(width 0.1)
				(type default)
			)
			(layer "F.Fab")
		)
		(fp_line
			(start 0.120396 0.2794)
			(end -0.12065 0.2794)
			(stroke
				(width 0.1)
				(type default)
			)
			(layer "F.Fab")
		)
		(fp_line
			(start -0.12065 0.3048)
			(end -0.67945 0.3048)
			(stroke
				(width 0.1)
				(type default)
			)
			(layer "F.Fab")
		)
		(fp_line
			(start -0.12065 0.2794)
			(end -0.12065 0.3048)
			(stroke
				(width 0.1)
				(type default)
			)
			(layer "F.Fab")
		)
		(fp_line
			(start -0.12065 -0.2794)
			(end 0.12065 -0.2794)
			(stroke
				(width 0.1)
				(type default)
			)
			(layer "F.Fab")
		)
		(fp_line
			(start -0.12065 -0.305054)
			(end -0.12065 -0.2794)
			(stroke
				(width 0.1)
				(type default)
			)
			(layer "F.Fab")
		)
		(fp_line
			(start -0.67945 0.3048)
			(end -0.67945 -0.305054)
			(stroke
				(width 0.1)
				(type default)
			)
			(layer "F.Fab")
		)
		(fp_line
			(start -0.67945 -0.305054)
			(end -0.12065 -0.305054)
			(stroke
				(width 0.1)
				(type default)
			)
			(layer "F.Fab")
		)
		(pad "1" smd circle
			(at -0.40005 0 180)
			(size 0 0)
			(layers "F.Cu" "F.Mask" "F.Paste")
			(net "P1V8_AUX")
		)
		(pad "2" smd circle
			(at 0.40005 0 180)
			(size 0 0)
			(layers "F.Cu" "F.Mask" "F.Paste")
			(net "P3V3_P1V8_I2C_I3C")
		)
	)
	(footprint ""
		(layer "F.Cu")
		(at 56.204612 -34.637726 -90)
		(property "Reference" "R19"
			(at 0 0 270)
			(layer "F.SilkS")
			(hide yes)
			(effects
				(font
					(size 1.27 1.27)
				)
			)
		)
		(property "Value" ""
			(at 0 0 270)
			(layer "F.Fab")
			(effects
				(font
					(size 1.27 1.27)
				)
			)
		)
		(duplicate_pad_numbers_are_jumpers no)
		(fp_line
			(start -0.7874 0.4064)
			(end -0.7874 -0.4064)
			(stroke
				(width 0.1524)
				(type default)
			)
			(layer "F.SilkS")
		)
		(fp_line
			(start 0.7874 0.4064)
			(end -0.7874 0.4064)
			(stroke
				(width 0.1524)
				(type default)
			)
			(layer "F.SilkS")
		)
		(fp_line
			(start -0.7874 -0.4064)
			(end 0.7874 -0.4064)
			(stroke
				(width 0.1524)
				(type default)
			)
			(layer "F.SilkS")
		)
		(fp_line
			(start 0.7874 -0.4064)
			(end 0.7874 0.4064)
			(stroke
				(width 0.1524)
				(type default)
			)
			(layer "F.SilkS")
		)
		(fp_line
			(start -0.67945 0.3048)
			(end -0.67945 -0.305054)
			(stroke
				(width 0.1)
				(type default)
			)
			(layer "F.Fab")
		)
		(fp_line
			(start -0.12065 0.3048)
			(end -0.67945 0.3048)
			(stroke
				(width 0.1)
				(type default)
			)
			(layer "F.Fab")
		)
		(fp_line
			(start 0.120396 0.3048)
			(end 0.120396 0.2794)
			(stroke
				(width 0.1)
				(type default)
			)
			(layer "F.Fab")
		)
		(fp_line
			(start 0.67945 0.3048)
			(end 0.120396 0.3048)
			(stroke
				(width 0.1)
				(type default)
			)
			(layer "F.Fab")
		)
		(fp_line
			(start -0.12065 0.2794)
			(end -0.12065 0.3048)
			(stroke
				(width 0.1)
				(type default)
			)
			(layer "F.Fab")
		)
		(fp_line
			(start 0.120396 0.2794)
			(end -0.12065 0.2794)
			(stroke
				(width 0.1)
				(type default)
			)
			(layer "F.Fab")
		)
		(fp_line
			(start -0.12065 -0.2794)
			(end 0.12065 -0.2794)
			(stroke
				(width 0.1)
				(type default)
			)
			(layer "F.Fab")
		)
		(fp_line
			(start 0.12065 -0.2794)
			(end 0.12065 -0.3048)
			(stroke
				(width 0.1)
				(type default)
			)
			(layer "F.Fab")
		)
		(fp_line
			(start 0.12065 -0.3048)
			(end 0.67945 -0.3048)
			(stroke
				(width 0.1)
				(type default)
			)
			(layer "F.Fab")
		)
		(fp_line
			(start 0.67945 -0.3048)
			(end 0.67945 0.3048)
			(stroke
				(width 0.1)
				(type default)
			)
			(layer "F.Fab")
		)
		(fp_line
			(start -0.67945 -0.305054)
			(end -0.12065 -0.305054)
			(stroke
				(width 0.1)
				(type default)
			)
			(layer "F.Fab")
		)
		(fp_line
			(start -0.12065 -0.305054)
			(end -0.12065 -0.2794)
			(stroke
				(width 0.1)
				(type default)
			)
			(layer "F.Fab")
		)
		(pad "1" smd circle
			(at -0.40005 0 270)
			(size 0 0)
			(layers "F.Cu" "F.Mask" "F.Paste")
			(net "V_VGAHS_R")
		)
		(pad "2" smd circle
			(at 0.40005 0 270)
			(size 0 0)
			(layers "F.Cu" "F.Mask" "F.Paste")
			(net "V_VGAHS")
		)
	)
)
